(kicad_pcb
	(version 20260206)
	(generator "pcbnew")
	(generator_version "10.0")
	(general
		(thickness 1.6)
		(legacy_teardrops no)
	)
	(paper "A4")
	(title_block
		(title "12092022_DA0F0TFB6D0_F0T_FAN_BOARD_MP5048_D_brd_v02_OCP.brd")
		(comment 1 "Grand Teton / footprints 191-196 of 924")
	)
	(layers
		(0 "F.Cu" signal "TOP")
		(4 "In1.Cu" signal "GND")
		(6 "In2.Cu" signal "IN1")
		(8 "In3.Cu" signal "IN2")
		(10 "In4.Cu" signal "GND1")
		(2 "B.Cu" signal "BOTTOM")
		(9 "F.Adhes" user "F.Adhesive")
		(11 "B.Adhes" user "B.Adhesive")
		(13 "F.Paste" user "Package Geometry/Pastemask Top")
		(15 "B.Paste" user "Package Geometry/Pastemask Bottom")
		(5 "F.SilkS" user "Ref Des/Silkscreen Top")
		(7 "B.SilkS" user "Ref Des/Silkscreen Bottom")
		(1 "F.Mask" user "Board Geometry/Soldermask Top")
		(3 "B.Mask" user "Board Geometry/Soldermask Bottom")
		(17 "Dwgs.User" user "User.Drawings")
		(19 "Cmts.User" user "User.Comments")
		(21 "Eco1.User" user "User.Eco1")
		(23 "Eco2.User" user "User.Eco2")
		(25 "Edge.Cuts" user "Board Geometry/Outline")
		(27 "Margin" user)
		(31 "F.CrtYd" user "Package Geometry/Place Bound Top")
		(29 "B.CrtYd" user "Package Geometry/Place Bound Bottom")
		(35 "F.Fab" user "Ref Des/Assembly Top")
		(33 "B.Fab" user "Ref Des/Assembly Bottom")
	)
	(footprint ""
		(layer "F.Cu")
		(at 21.59 -143.891 -90)
		(property "Reference" "R4785"
			(at 0 0 270)
			(layer "F.SilkS")
			(hide yes)
			(effects
				(font
					(size 1.27 1.27)
				)
			)
		)
		(property "Value" ""
			(at 0 0 270)
			(layer "F.Fab")
			(effects
				(font
					(size 1.27 1.27)
				)
			)
		)
		(duplicate_pad_numbers_are_jumpers no)
		(fp_line
			(start -0.7874 0.4064)
			(end -0.7874 -0.4064)
			(stroke
				(width 0.1524)
				(type default)
			)
			(layer "F.SilkS")
		)
		(fp_line
			(start 0.7874 0.4064)
			(end -0.7874 0.4064)
			(stroke
				(width 0.1524)
				(type default)
			)
			(layer "F.SilkS")
		)
		(fp_line
			(start -0.7874 -0.4064)
			(end 0.7874 -0.4064)
			(stroke
				(width 0.1524)
				(type default)
			)
			(layer "F.SilkS")
		)
		(fp_line
			(start 0.7874 -0.4064)
			(end 0.7874 0.4064)
			(stroke
				(width 0.1524)
				(type default)
			)
			(layer "F.SilkS")
		)
		(fp_line
			(start -0.67945 0.3048)
			(end -0.67945 -0.305054)
			(stroke
				(width 0.1)
				(type default)
			)
			(layer "F.Fab")
		)
		(fp_line
			(start -0.12065 0.3048)
			(end -0.67945 0.3048)
			(stroke
				(width 0.1)
				(type default)
			)
			(layer "F.Fab")
		)
		(fp_line
			(start 0.120396 0.3048)
			(end 0.120396 0.2794)
			(stroke
				(width 0.1)
				(type default)
			)
			(layer "F.Fab")
		)
		(fp_line
			(start 0.67945 0.3048)
			(end 0.120396 0.3048)
			(stroke
				(width 0.1)
				(type default)
			)
			(layer "F.Fab")
		)
		(fp_line
			(start -0.12065 0.2794)
			(end -0.12065 0.3048)
			(stroke
				(width 0.1)
				(type default)
			)
			(layer "F.Fab")
		)
		(fp_line
			(start 0.120396 0.2794)
			(end -0.12065 0.2794)
			(stroke
				(width 0.1)
				(type default)
			)
			(layer "F.Fab")
		)
		(fp_line
			(start -0.12065 -0.2794)
			(end 0.12065 -0.2794)
			(stroke
				(width 0.1)
				(type default)
			)
			(layer "F.Fab")
		)
		(fp_line
			(start 0.12065 -0.2794)
			(end 0.12065 -0.3048)
			(stroke
				(width 0.1)
				(type default)
			)
			(layer "F.Fab")
		)
		(fp_line
			(start 0.12065 -0.3048)
			(end 0.67945 -0.3048)
			(stroke
				(width 0.1)
				(type default)
			)
			(layer "F.Fab")
		)
		(fp_line
			(start 0.67945 -0.3048)
			(end 0.67945 0.3048)
			(stroke
				(width 0.1)
				(type default)
			)
			(layer "F.Fab")
		)
		(fp_line
			(start -0.67945 -0.305054)
			(end -0.12065 -0.305054)
			(stroke
				(width 0.1)
				(type default)
			)
			(layer "F.Fab")
		)
		(fp_line
			(start -0.12065 -0.305054)
			(end -0.12065 -0.2794)
			(stroke
				(width 0.1)
				(type default)
			)
			(layer "F.Fab")
		)
		(pad "1" smd circle
			(at -0.40005 0 270)
			(size 0 0)
			(layers "F.Cu" "F.Mask" "F.Paste")
			(net "SMB_FAN0_R_SDA")
		)
		(pad "2" smd circle
			(at 0.40005 0 270)
			(size 0 0)
			(layers "F.Cu" "F.Mask" "F.Paste")
			(net "SMB_FAN0_SDA")
		)
	)
	(footprint ""
		(layer "F.Cu")
		(at 19.05 -146.05 90)
		(property "Reference" "R5473"
			(at 0 0 90)
			(layer "F.SilkS")
			(hide yes)
			(effects
				(font
					(size 1.27 1.27)
				)
			)
		)
		(property "Value" ""
			(at 0 0 90)
			(layer "F.Fab")
			(effects
				(font
					(size 1.27 1.27)
				)
			)
		)
		(duplicate_pad_numbers_are_jumpers no)
		(fp_line
			(start 0.7874 -0.4064)
			(end 0.7874 0.4064)
			(stroke
				(width 0.1524)
				(type default)
			)
			(layer "F.SilkS")
		)
		(fp_line
			(start -0.7874 -0.4064)
			(end 0.7874 -0.4064)
			(stroke
				(width 0.1524)
				(type default)
			)
			(layer "F.SilkS")
		)
		(fp_line
			(start 0.7874 0.4064)
			(end -0.7874 0.4064)
			(stroke
				(width 0.1524)
				(type default)
			)
			(layer "F.SilkS")
		)
		(fp_line
			(start -0.7874 0.4064)
			(end -0.7874 -0.4064)
			(stroke
				(width 0.1524)
				(type default)
			)
			(layer "F.SilkS")
		)
		(fp_line
			(start -0.12065 -0.305054)
			(end -0.12065 -0.2794)
			(stroke
				(width 0.1)
				(type default)
			)
			(layer "F.Fab")
		)
		(fp_line
			(start -0.67945 -0.305054)
			(end -0.12065 -0.305054)
			(stroke
				(width 0.1)
				(type default)
			)
			(layer "F.Fab")
		)
		(fp_line
			(start 0.67945 -0.3048)
			(end 0.67945 0.3048)
			(stroke
				(width 0.1)
				(type default)
			)
			(layer "F.Fab")
		)
		(fp_line
			(start 0.12065 -0.3048)
			(end 0.67945 -0.3048)
			(stroke
				(width 0.1)
				(type default)
			)
			(layer "F.Fab")
		)
		(fp_line
			(start 0.12065 -0.2794)
			(end 0.12065 -0.3048)
			(stroke
				(width 0.1)
				(type default)
			)
			(layer "F.Fab")
		)
		(fp_line
			(start -0.12065 -0.2794)
			(end 0.12065 -0.2794)
			(stroke
				(width 0.1)
				(type default)
			)
			(layer "F.Fab")
		)
		(fp_line
			(start 0.120396 0.2794)
			(end -0.12065 0.2794)
			(stroke
				(width 0.1)
				(type default)
			)
			(layer "F.Fab")
		)
		(fp_line
			(start -0.12065 0.2794)
			(end -0.12065 0.3048)
			(stroke
				(width 0.1)
				(type default)
			)
			(layer "F.Fab")
		)
		(fp_line
			(start 0.67945 0.3048)
			(end 0.120396 0.3048)
			(stroke
				(width 0.1)
				(type default)
			)
			(layer "F.Fab")
		)
		(fp_line
			(start 0.120396 0.3048)
			(end 0.120396 0.2794)
			(stroke
				(width 0.1)
				(type default)
			)
			(layer "F.Fab")
		)
		(fp_line
			(start -0.12065 0.3048)
			(end -0.67945 0.3048)
			(stroke
				(width 0.1)
				(type default)
			)
			(layer "F.Fab")
		)
		(fp_line
			(start -0.67945 0.3048)
			(end -0.67945 -0.305054)
			(stroke
				(width 0.1)
				(type default)
			)
			(layer "F.Fab")
		)
		(pad "1" smd circle
			(at -0.40005 0 90)
			(size 0 0)
			(layers "F.Cu" "F.Mask" "F.Paste")
			(net "P3V3_AUX")
		)
		(pad "2" smd circle
			(at 0.40005 0 90)
			(size 0 0)
			(layers "F.Cu" "F.Mask" "F.Paste")
			(net "PD_TCA9548_SML1_U321_A1")
		)
	)
	(footprint ""
		(layer "F.Cu")
		(at 35.306 -211.864956 180)
		(property "Reference" "C2028"
			(at 0 0 180)
			(layer "F.SilkS")
			(hide yes)
			(effects
				(font
					(size 1.27 1.27)
				)
			)
		)
		(property "Value" ""
			(at 0 0 180)
			(layer "F.Fab")
			(effects
				(font
					(size 1.27 1.27)
				)
			)
		)
		(duplicate_pad_numbers_are_jumpers no)
		(fp_line
			(start 0.7874 0.4064)
			(end -0.7874 0.4064)
			(stroke
				(width 0.1524)
				(type default)
			)
			(layer "F.SilkS")
		)
		(fp_line
			(start 0.7874 -0.4064)
			(end 0.7874 0.4064)
			(stroke
				(width 0.1524)
				(type default)
			)
			(layer "F.SilkS")
		)
		(fp_line
			(start -0.7874 0.4064)
			(end -0.7874 -0.4064)
			(stroke
				(width 0.1524)
				(type default)
			)
			(layer "F.SilkS")
		)
		(fp_line
			(start -0.7874 -0.4064)
			(end 0.7874 -0.4064)
			(stroke
				(width 0.1524)
				(type default)
			)
			(layer "F.SilkS")
		)
		(fp_line
			(start 0.67945 0.3048)
			(end 0.120396 0.3048)
			(stroke
				(width 0.1)
				(type default)
			)
			(layer "F.Fab")
		)
		(fp_line
			(start 0.67945 -0.3048)
			(end 0.67945 0.3048)
			(stroke
				(width 0.1)
				(type default)
			)
			(layer "F.Fab")
		)
		(fp_line
			(start 0.12065 -0.2794)
			(end 0.12065 -0.3048)
			(stroke
				(width 0.1)
				(type default)
			)
			(layer "F.Fab")
		)
		(fp_line
			(start 0.12065 -0.3048)
			(end 0.67945 -0.3048)
			(stroke
				(width 0.1)
				(type default)
			)
			(layer "F.Fab")
		)
		(fp_line
			(start 0.120396 0.3048)
			(end 0.120396 0.2794)
			(stroke
				(width 0.1)
				(type default)
			)
			(layer "F.Fab")
		)
		(fp_line
			(start 0.120396 0.2794)
			(end -0.12065 0.2794)
			(stroke
				(width 0.1)
				(type default)
			)
			(layer "F.Fab")
		)
		(fp_line
			(start -0.12065 0.3048)
			(end -0.67945 0.3048)
			(stroke
				(width 0.1)
				(type default)
			)
			(layer "F.Fab")
		)
		(fp_line
			(start -0.12065 0.2794)
			(end -0.12065 0.3048)
			(stroke
				(width 0.1)
				(type default)
			)
			(layer "F.Fab")
		)
		(fp_line
			(start -0.12065 -0.2794)
			(end 0.12065 -0.2794)
			(stroke
				(width 0.1)
				(type default)
			)
			(layer "F.Fab")
		)
		(fp_line
			(start -0.12065 -0.305054)
			(end -0.12065 -0.2794)
			(stroke
				(width 0.1)
				(type default)
			)
			(layer "F.Fab")
		)
		(fp_line
			(start -0.67945 0.3048)
			(end -0.67945 -0.305054)
			(stroke
				(width 0.1)
				(type default)
			)
			(layer "F.Fab")
		)
		(fp_line
			(start -0.67945 -0.305054)
			(end -0.12065 -0.305054)
			(stroke
				(width 0.1)
				(type default)
			)
			(layer "F.Fab")
		)
		(pad "1" smd circle
			(at -0.40005 0 180)
			(size 0 0)
			(layers "F.Cu" "F.Mask" "F.Paste")
			(net "FAN_1_PWM_OL_R")
		)
		(pad "2" smd circle
			(at 0.40005 0 180)
			(size 0 0)
			(layers "F.Cu" "F.Mask" "F.Paste")
			(net "GND")
		)
	)
	(footprint ""
		(layer "F.Cu")
		(at 23.241 -28.194 -90)
		(property "Reference" "R5514"
			(at 0 0 270)
			(layer "F.SilkS")
			(hide yes)
			(effects
				(font
					(size 1.27 1.27)
				)
			)
		)
		(property "Value" ""
			(at 0 0 270)
			(layer "F.Fab")
			(effects
				(font
					(size 1.27 1.27)
				)
			)
		)
		(duplicate_pad_numbers_are_jumpers no)
		(fp_line
			(start -0.7874 0.4064)
			(end -0.7874 -0.4064)
			(stroke
				(width 0.1524)
				(type default)
			)
			(layer "F.SilkS")
		)
		(fp_line
			(start 0.7874 0.4064)
			(end -0.7874 0.4064)
			(stroke
				(width 0.1524)
				(type default)
			)
			(layer "F.SilkS")
		)
		(fp_line
			(start -0.7874 -0.4064)
			(end 0.7874 -0.4064)
			(stroke
				(width 0.1524)
				(type default)
			)
			(layer "F.SilkS")
		)
		(fp_line
			(start 0.7874 -0.4064)
			(end 0.7874 0.4064)
			(stroke
				(width 0.1524)
				(type default)
			)
			(layer "F.SilkS")
		)
		(fp_line
			(start -0.67945 0.3048)
			(end -0.67945 -0.305054)
			(stroke
				(width 0.1)
				(type default)
			)
			(layer "F.Fab")
		)
		(fp_line
			(start -0.12065 0.3048)
			(end -0.67945 0.3048)
			(stroke
				(width 0.1)
				(type default)
			)
			(layer "F.Fab")
		)
		(fp_line
			(start 0.120396 0.3048)
			(end 0.120396 0.2794)
			(stroke
				(width 0.1)
				(type default)
			)
			(layer "F.Fab")
		)
		(fp_line
			(start 0.67945 0.3048)
			(end 0.120396 0.3048)
			(stroke
				(width 0.1)
				(type default)
			)
			(layer "F.Fab")
		)
		(fp_line
			(start -0.12065 0.2794)
			(end -0.12065 0.3048)
			(stroke
				(width 0.1)
				(type default)
			)
			(layer "F.Fab")
		)
		(fp_line
			(start 0.120396 0.2794)
			(end -0.12065 0.2794)
			(stroke
				(width 0.1)
				(type default)
			)
			(layer "F.Fab")
		)
		(fp_line
			(start -0.12065 -0.2794)
			(end 0.12065 -0.2794)
			(stroke
				(width 0.1)
				(type default)
			)
			(layer "F.Fab")
		)
		(fp_line
			(start 0.12065 -0.2794)
			(end 0.12065 -0.3048)
			(stroke
				(width 0.1)
				(type default)
			)
			(layer "F.Fab")
		)
		(fp_line
			(start 0.12065 -0.3048)
			(end 0.67945 -0.3048)
			(stroke
				(width 0.1)
				(type default)
			)
			(layer "F.Fab")
		)
		(fp_line
			(start 0.67945 -0.3048)
			(end 0.67945 0.3048)
			(stroke
				(width 0.1)
				(type default)
			)
			(layer "F.Fab")
		)
		(fp_line
			(start -0.67945 -0.305054)
			(end -0.12065 -0.305054)
			(stroke
				(width 0.1)
				(type default)
			)
			(layer "F.Fab")
		)
		(fp_line
			(start -0.12065 -0.305054)
			(end -0.12065 -0.2794)
			(stroke
				(width 0.1)
				(type default)
			)
			(layer "F.Fab")
		)
		(pad "1" smd circle
			(at -0.40005 0 270)
			(size 0 0)
			(layers "F.Cu" "F.Mask" "F.Paste")
			(net "P3V3_AUX")
		)
		(pad "2" smd circle
			(at 0.40005 0 270)
			(size 0 0)
			(layers "F.Cu" "F.Mask" "F.Paste")
			(net "FAN_3_PWM_BUF")
		)
	)
	(footprint ""
		(layer "F.Cu")
		(at 22.098 -160.02 90)
		(property "Reference" "R4883"
			(at 0 0 90)
			(layer "F.SilkS")
			(hide yes)
			(effects
				(font
					(size 1.27 1.27)
				)
			)
		)
		(property "Value" ""
			(at 0 0 90)
			(layer "F.Fab")
			(effects
				(font
					(size 1.27 1.27)
				)
			)
		)
		(duplicate_pad_numbers_are_jumpers no)
		(fp_line
			(start 0.7874 -0.4064)
			(end 0.7874 0.4064)
			(stroke
				(width 0.1524)
				(type default)
			)
			(layer "F.SilkS")
		)
		(fp_line
			(start -0.7874 -0.4064)
			(end 0.7874 -0.4064)
			(stroke
				(width 0.1524)
				(type default)
			)
			(layer "F.SilkS")
		)
		(fp_line
			(start 0.7874 0.4064)
			(end -0.7874 0.4064)
			(stroke
				(width 0.1524)
				(type default)
			)
			(layer "F.SilkS")
		)
		(fp_line
			(start -0.7874 0.4064)
			(end -0.7874 -0.4064)
			(stroke
				(width 0.1524)
				(type default)
			)
			(layer "F.SilkS")
		)
		(fp_line
			(start -0.12065 -0.305054)
			(end -0.12065 -0.2794)
			(stroke
				(width 0.1)
				(type default)
			)
			(layer "F.Fab")
		)
		(fp_line
			(start -0.67945 -0.305054)
			(end -0.12065 -0.305054)
			(stroke
				(width 0.1)
				(type default)
			)
			(layer "F.Fab")
		)
		(fp_line
			(start 0.67945 -0.3048)
			(end 0.67945 0.3048)
			(stroke
				(width 0.1)
				(type default)
			)
			(layer "F.Fab")
		)
		(fp_line
			(start 0.12065 -0.3048)
			(end 0.67945 -0.3048)
			(stroke
				(width 0.1)
				(type default)
			)
			(layer "F.Fab")
		)
		(fp_line
			(start 0.12065 -0.2794)
			(end 0.12065 -0.3048)
			(stroke
				(width 0.1)
				(type default)
			)
			(layer "F.Fab")
		)
		(fp_line
			(start -0.12065 -0.2794)
			(end 0.12065 -0.2794)
			(stroke
				(width 0.1)
				(type default)
			)
			(layer "F.Fab")
		)
		(fp_line
			(start 0.120396 0.2794)
			(end -0.12065 0.2794)
			(stroke
				(width 0.1)
				(type default)
			)
			(layer "F.Fab")
		)
		(fp_line
			(start -0.12065 0.2794)
			(end -0.12065 0.3048)
			(stroke
				(width 0.1)
				(type default)
			)
			(layer "F.Fab")
		)
		(fp_line
			(start 0.67945 0.3048)
			(end 0.120396 0.3048)
			(stroke
				(width 0.1)
				(type default)
			)
			(layer "F.Fab")
		)
		(fp_line
			(start 0.120396 0.3048)
			(end 0.120396 0.2794)
			(stroke
				(width 0.1)
				(type default)
			)
			(layer "F.Fab")
		)
		(fp_line
			(start -0.12065 0.3048)
			(end -0.67945 0.3048)
			(stroke
				(width 0.1)
				(type default)
			)
			(layer "F.Fab")
		)
		(fp_line
			(start -0.67945 0.3048)
			(end -0.67945 -0.305054)
			(stroke
				(width 0.1)
				(type default)
			)
			(layer "F.Fab")
		)
		(pad "1" smd circle
			(at -0.40005 0 90)
			(size 0 0)
			(layers "F.Cu" "F.Mask" "F.Paste")
			(net "SMB_FAN7_R_SCL")
		)
		(pad "2" smd circle
			(at 0.40005 0 90)
			(size 0 0)
			(layers "F.Cu" "F.Mask" "F.Paste")
			(net "SMB_FAN7_SCL")
		)
	)
	(footprint ""
		(layer "F.Cu")
		(at 25.527 -131.445 180)
		(property "Reference" "R4941"
			(at 0 0 180)
			(layer "F.SilkS")
			(hide yes)
			(effects
				(font
					(size 1.27 1.27)
				)
			)
		)
		(property "Value" ""
			(at 0 0 180)
			(layer "F.Fab")
			(effects
				(font
					(size 1.27 1.27)
				)
			)
		)
		(duplicate_pad_numbers_are_jumpers no)
		(fp_line
			(start 0.7874 0.4064)
			(end -0.7874 0.4064)
			(stroke
				(width 0.1524)
				(type default)
			)
			(layer "F.SilkS")
		)
		(fp_line
			(start 0.7874 -0.4064)
			(end 0.7874 0.4064)
			(stroke
				(width 0.1524)
				(type default)
			)
			(layer "F.SilkS")
		)
		(fp_line
			(start -0.7874 0.4064)
			(end -0.7874 -0.4064)
			(stroke
				(width 0.1524)
				(type default)
			)
			(layer "F.SilkS")
		)
		(fp_line
			(start -0.7874 -0.4064)
			(end 0.7874 -0.4064)
			(stroke
				(width 0.1524)
				(type default)
			)
			(layer "F.SilkS")
		)
		(fp_line
			(start 0.67945 0.3048)
			(end 0.120396 0.3048)
			(stroke
				(width 0.1)
				(type default)
			)
			(layer "F.Fab")
		)
		(fp_line
			(start 0.67945 -0.3048)
			(end 0.67945 0.3048)
			(stroke
				(width 0.1)
				(type default)
			)
			(layer "F.Fab")
		)
		(fp_line
			(start 0.12065 -0.2794)
			(end 0.12065 -0.3048)
			(stroke
				(width 0.1)
				(type default)
			)
			(layer "F.Fab")
		)
		(fp_line
			(start 0.12065 -0.3048)
			(end 0.67945 -0.3048)
			(stroke
				(width 0.1)
				(type default)
			)
			(layer "F.Fab")
		)
		(fp_line
			(start 0.120396 0.3048)
			(end 0.120396 0.2794)
			(stroke
				(width 0.1)
				(type default)
			)
			(layer "F.Fab")
		)
		(fp_line
			(start 0.120396 0.2794)
			(end -0.12065 0.2794)
			(stroke
				(width 0.1)
				(type default)
			)
			(layer "F.Fab")
		)
		(fp_line
			(start -0.12065 0.3048)
			(end -0.67945 0.3048)
			(stroke
				(width 0.1)
				(type default)
			)
			(layer "F.Fab")
		)
		(fp_line
			(start -0.12065 0.2794)
			(end -0.12065 0.3048)
			(stroke
				(width 0.1)
				(type default)
			)
			(layer "F.Fab")
		)
		(fp_line
			(start -0.12065 -0.2794)
			(end 0.12065 -0.2794)
			(stroke
				(width 0.1)
				(type default)
			)
			(layer "F.Fab")
		)
		(fp_line
			(start -0.12065 -0.305054)
			(end -0.12065 -0.2794)
			(stroke
				(width 0.1)
				(type default)
			)
			(layer "F.Fab")
		)
		(fp_line
			(start -0.67945 0.3048)
			(end -0.67945 -0.305054)
			(stroke
				(width 0.1)
				(type default)
			)
			(layer "F.Fab")
		)
		(fp_line
			(start -0.67945 -0.305054)
			(end -0.12065 -0.305054)
			(stroke
				(width 0.1)
				(type default)
			)
			(layer "F.Fab")
		)
		(pad "1" smd circle
			(at -0.40005 0 180)
			(size 0 0)
			(layers "F.Cu" "F.Mask" "F.Paste")
			(net "MAX31790_U317_PWM_START0")
		)
		(pad "2" smd circle
			(at 0.40005 0 180)
			(size 0 0)
			(layers "F.Cu" "F.Mask" "F.Paste")
			(net "P3V3_AUX")
		)
	)
)
